%FSTAX25Y25*%
%MOIN*%
%SFA1B1*%

%IPPOS*%
%ADD13C,0.003940*%
%ADD14C,0.010000*%
%ADD168C,0.000000*%
%LNgrandmaster-1*%
%LPD*%
G54D13*
X0776138Y0543501D02*
D01*
X077612Y0544002*
X0776068Y05445*
X077598Y0544994*
X0775859Y0545481*
X0775704Y0545958*
X0775516Y0546423*
X0775296Y0546874*
X0775046Y0547308*
X0774765Y0547724*
X0774457Y0548119*
X0774121Y0548492*
X077376Y054884*
X0773376Y0549162*
X077297Y0549457*
X0772545Y0549723*
X0772102Y0549958*
X0771644Y0550162*
X0771173Y0550334*
X0770691Y0550472*
X07702Y0550576*
X0769704Y0550646*
X0769203Y0550681*
X0768702*
X0768201Y0550646*
X0767705Y0550576*
X0767214Y0550472*
X0766732Y0550334*
X0766261Y0550162*
X0765803Y0549958*
X076536Y0549723*
X0764935Y0549457*
X0764529Y0549162*
X0764145Y054884*
X0763784Y0548492*
X0763448Y0548119*
X076314Y0547724*
X0762859Y0547308*
X0762609Y0546874*
X0762389Y0546423*
X0762201Y0545958*
X0762046Y0545481*
X0761925Y0544994*
X0761837Y05445*
X0761785Y0544002*
X0761768Y0543501*
X0598972Y0518205D02*
X0658028D01*
Y0550686*
X0730272*
Y0518205D02*
Y0550686D01*
Y0518205D02*
X0761768D01*
Y0543501*
G54D14*
X133991Y0937169D02*
D01*
X1339884Y0937192*
X1339857Y0937214*
X1339829Y0937235*
X1339799Y0937253*
X1339768Y0937269*
X1339736Y0937282*
X1339703Y0937294*
X1339669Y0937303*
X1339635Y093731*
X13396Y0937314*
X1339565Y0937316*
X1339555Y0937317*
X1340105Y0936767D02*
D01*
X1340103Y0936801*
X13401Y0936836*
X1340094Y093687*
X1340085Y0936904*
X1340074Y0936938*
X1340061Y093697*
X1340046Y0937001*
X1340029Y0937031*
X1340009Y093706*
X1339988Y0937088*
X1339964Y0937114*
X1339959Y0937121*
X1339909Y0937171D02*
D01*
X1339883Y0937194*
X1339856Y0937216*
X1339827Y0937236*
X1339797Y0937254*
X1339766Y093727*
X1339734Y0937284*
X1339701Y0937295*
X1339667Y0937304*
X1339633Y0937311*
X1339598Y0937315*
X1339563Y0937317*
X1339555Y0937317*
X1340105Y0936767D02*
D01*
X1340103Y0936801*
X13401Y0936836*
X1340094Y093687*
X1340085Y0936904*
X1340074Y0936938*
X1340061Y093697*
X1340046Y0937001*
X1340029Y0937031*
X1340009Y093706*
X1339988Y0937088*
X1339964Y0937114*
X1339957Y0937122*
X1339959Y0550231D02*
D01*
X1339982Y0550256*
X1340004Y0550283*
X1340024Y0550312*
X1340042Y0550342*
X1340058Y0550373*
X1340072Y0550405*
X1340083Y0550438*
X1340092Y0550472*
X1340099Y0550506*
X1340103Y0550541*
X1340105Y0550576*
X1340105Y0550585*
X1339957Y055023D02*
D01*
X133998Y0550255*
X1340002Y0550282*
X1340023Y055031*
X1340041Y055034*
X1340057Y0550371*
X134007Y0550403*
X1340082Y0550436*
X1340091Y055047*
X1340098Y0550504*
X1340102Y0550539*
X1340104Y0550574*
X1340105Y0550585*
X1339555Y0550035D02*
D01*
X1339589Y0550036*
X1339624Y0550039*
X1339658Y0550045*
X1339692Y0550054*
X1339726Y0550065*
X1339758Y0550078*
X1339789Y0550093*
X1339819Y055011*
X1339848Y055013*
X1339876Y0550151*
X1339902Y0550175*
X133991Y0550183*
X1339555Y0550035D02*
D01*
X1339589Y0550036*
X1339624Y0550039*
X1339658Y0550045*
X1339692Y0550054*
X1339726Y0550065*
X1339758Y0550078*
X1339789Y0550093*
X1339819Y055011*
X1339848Y055013*
X1339876Y0550151*
X1339902Y0550175*
X1339909Y0550181*
X0911254Y0551035D02*
D01*
X0911219Y0551033*
X0911184Y055103*
X091115Y0551024*
X0911116Y0551015*
X0911082Y0551004*
X091105Y0550991*
X0911019Y0550976*
X0910989Y0550959*
X091096Y0550939*
X0910932Y0550918*
X0910906Y0550894*
X0910882Y0550869*
X0910859Y0550842*
X0910839Y0550814*
X091082Y0550785*
X0910804Y0550754*
X091079Y0550722*
X0910778Y0550689*
X0910768Y0550655*
X0910761Y0550621*
X0910756Y0550587*
X0910754Y0550552*
X0910754Y0550535*
X0911254Y0551035D02*
D01*
X0911219Y0551033*
X0911184Y055103*
X091115Y0551024*
X0911116Y0551015*
X0911082Y0551004*
X091105Y0550991*
X0911019Y0550976*
X0910989Y0550959*
X091096Y0550939*
X0910932Y0550918*
X0910906Y0550894*
X0910882Y0550869*
X0910859Y0550842*
X0910839Y0550814*
X091082Y0550785*
X0910804Y0550754*
X091079Y0550722*
X0910778Y0550689*
X0910768Y0550655*
X0910761Y0550621*
X0910756Y0550587*
X0910754Y0550552*
X0910754Y0550535*
X0828204Y0529885D02*
D01*
X0828193Y0530174*
X0828163Y0530462*
X0828113Y0530747*
X0828043Y0531028*
X0827953Y0531304*
X0827845Y0531572*
X0827718Y0531833*
X0827573Y0532084*
X0827411Y0532324*
X0827233Y0532552*
X0827039Y0532767*
X082683Y0532969*
X0826608Y0533155*
X0826374Y0533325*
X0826129Y0533479*
X0825873Y0533614*
X0825608Y0533732*
X0825336Y0533831*
X0825057Y0533911*
X0824774Y0533971*
X0824487Y0534012*
X0824198Y0534032*
X0824054Y0534035*
X0827204Y0529885D02*
D01*
X0827196Y0530104*
X0827173Y0530323*
X0827135Y0530539*
X0827081Y0530753*
X0827014Y0530962*
X0826931Y0531166*
X0826835Y0531363*
X0826725Y0531554*
X0826602Y0531736*
X0826467Y0531909*
X0826319Y0532073*
X0826161Y0532225*
X0825993Y0532367*
X0825815Y0532496*
X0825629Y0532612*
X0825434Y0532716*
X0825234Y0532805*
X0825027Y053288*
X0824816Y0532941*
X08246Y0532987*
X0824383Y0533017*
X0824163Y0533033*
X0824054Y0533035*
X0823954Y0534035D02*
D01*
X0823664Y0534024*
X0823376Y0533994*
X0823091Y0533944*
X082281Y0533874*
X0822534Y0533784*
X0822266Y0533676*
X0822005Y0533549*
X0821754Y0533404*
X0821514Y0533242*
X0821286Y0533064*
X0821071Y053287*
X0820869Y0532661*
X0820683Y0532439*
X0820513Y0532205*
X0820359Y053196*
X0820224Y0531704*
X0820106Y0531439*
X0820007Y0531167*
X0819927Y0530888*
X0819867Y0530605*
X0819826Y0530318*
X0819806Y0530029*
X0819804Y0529885*
X0823954Y0533035D02*
D01*
X0823734Y0533027*
X0823515Y0533004*
X0823299Y0532966*
X0823085Y0532912*
X0822876Y0532845*
X0822672Y0532762*
X0822475Y0532666*
X0822284Y0532556*
X0822102Y0532433*
X0821929Y0532298*
X0821765Y053215*
X0821613Y0531992*
X0821471Y0531824*
X0821342Y0531646*
X0821226Y053146*
X0821122Y0531265*
X0821033Y0531065*
X0820958Y0530858*
X0820897Y0530647*
X0820851Y0530431*
X0820821Y0530214*
X0820805Y0529994*
X0820804Y0529885*
X0911716Y0502294D02*
D01*
X0911728Y0502326*
X0911738Y050236*
X0911745Y0502394*
X091175Y0502428*
X0911753Y0502463*
X0911754Y0502485*
X0911716Y0502295D02*
D01*
X0911728Y0502327*
X0911737Y0502361*
X0911745Y0502395*
X091175Y0502429*
X0911753Y0502464*
X0911754Y0502485*
X0911716Y0502293D02*
D01*
X0911716Y0502293*
X0911716Y0502293*
X0911716Y0502294*
X0911716Y0502294*
X0911716Y0502295*
X0911701Y0502257D02*
D01*
X0911701Y0502257*
X0911701Y0502257*
X0911701Y0502258*
X0911701Y0502258*
X0911701Y0502259*
X0911702*
X0911593Y0502096D02*
D01*
X0911616Y0502121*
X0911638Y0502148*
X0911658Y0502177*
X0911676Y0502207*
X0911692Y0502238*
X0911701Y0502257*
X0911591Y0502094D02*
D01*
X0911614Y0502119*
X0911636Y0502146*
X0911657Y0502174*
X0911675Y0502204*
X0911691Y0502235*
X0911701Y0502258*
X0909431Y0499988D02*
D01*
X0909462Y0500002*
X0909493Y0500019*
X0909522Y0500037*
X090955Y0500058*
X0909577Y0500081*
X0909595Y0500098*
X0909432Y0499988D02*
D01*
X0909463Y0500002*
X0909494Y0500019*
X0909523Y0500038*
X0909551Y0500058*
X0909578Y0500081*
X0909593Y0500096*
X090943Y0499987D02*
D01*
X090943Y0499987*
X090943Y0499987*
X0909431Y0499987*
X0909431Y0499987*
X0909432Y0499987*
Y0499988*
X0909394Y0499972D02*
D01*
X0909394Y0499972*
X0909394Y0499972*
X0909395Y0499972*
X0909395Y0499972*
X0909396Y0499972*
Y0499973*
X0909204Y0499935D02*
D01*
X0909238Y0499936*
X0909273Y0499939*
X0909307Y0499945*
X0909341Y0499954*
X0909375Y0499965*
X0909394Y0499972*
X0909204Y0499935D02*
D01*
X0909238Y0499936*
X0909273Y0499939*
X0909307Y0499945*
X0909341Y0499954*
X0909375Y0499965*
X0909395Y0499973*
X0829563D02*
D01*
X0829595Y049996*
X0829629Y049995*
X0829663Y0499943*
X0829697Y0499938*
X0829732Y0499935*
X0829754Y0499935*
X0829526Y0499988D02*
D01*
X0829526Y0499987*
X0829526Y0499987*
X0829527Y0499987*
X0829527Y0499987*
X0829528Y0499987*
Y0499987*
X0829365Y0500096D02*
D01*
X082939Y0500072*
X0829417Y050005*
X0829446Y050003*
X0829476Y0500012*
X0829507Y0499996*
X0829526Y0499988*
X0827204Y0502485D02*
D01*
X0827205Y050245*
X0827208Y0502415*
X0827214Y0502381*
X0827223Y0502347*
X0827234Y0502313*
X0827242Y0502294*
Y0502295D02*
D01*
X0827242Y0502294*
X0827242Y0502294*
X0827242Y0502293*
X0827242Y0502293*
X0827242Y0502293*
X0827204Y0502485D02*
D01*
X0827205Y050245*
X0827208Y0502415*
X0827214Y0502381*
X0827223Y0502347*
X0827234Y0502313*
X0827242Y0502295*
X0827257Y0502258D02*
D01*
X0827271Y0502226*
X0827288Y0502195*
X0827306Y0502166*
X0827327Y0502138*
X082735Y0502111*
X0827367Y0502094*
X0827257Y0502257D02*
D01*
X0827271Y0502225*
X0827288Y0502194*
X0827307Y0502165*
X0827327Y0502137*
X082735Y050211*
X0827365Y0502096*
X0827256Y0502259D02*
D01*
X0827256Y0502258*
X0827256Y0502258*
X0827256Y0502257*
X0827256Y0502257*
X0827257Y0502257*
X0820766Y0502294D02*
D01*
X0820778Y0502326*
X0820788Y050236*
X0820795Y0502394*
X08208Y0502428*
X0820803Y0502463*
X0820804Y0502485*
X0820767Y0502295D02*
D01*
X0820779Y0502327*
X0820788Y0502361*
X0820796Y0502395*
X0820801Y0502429*
X0820804Y0502464*
Y0502485*
X0820766Y0502293D02*
D01*
X0820766Y0502293*
X0820766Y0502293*
X0820766Y0502294*
X0820766Y0502294*
X0820766Y0502295*
X0820767*
X0820751Y0502257D02*
D01*
X0820751Y0502257*
X0820751Y0502257*
X0820751Y0502258*
X0820751Y0502258*
X0820751Y0502259*
X0820752*
X0820643Y0502096D02*
D01*
X0820666Y0502121*
X0820688Y0502148*
X0820708Y0502177*
X0820726Y0502207*
X0820742Y0502238*
X0820751Y0502257*
X0820641Y0502094D02*
D01*
X0820664Y0502119*
X0820686Y0502146*
X0820707Y0502174*
X0820725Y0502204*
X0820741Y0502235*
X0820751Y0502258*
X0829363Y0500098D02*
D01*
X0829388Y0500074*
X0829415Y0500052*
X0829443Y0500031*
X0829473Y0500013*
X0829504Y0499997*
X0829527Y0499988*
X0829564Y0499972D02*
D01*
X0829596Y0499959*
X082963Y049995*
X0829664Y0499942*
X0829698Y0499937*
X0829733Y0499934*
X0829754Y0499935*
X0829562Y0499973D02*
D01*
X0829562Y0499972*
X0829562Y0499972*
X0829563Y0499972*
X0829563Y0499972*
X0829564Y0499972*
Y0499972*
X0818481Y0499988D02*
D01*
X0818512Y0500002*
X0818543Y0500019*
X0818572Y0500037*
X08186Y0500058*
X0818627Y0500081*
X0818645Y0500098*
X0818444Y0499972D02*
D01*
X0818444Y0499972*
X0818444Y0499972*
X0818445Y0499972*
X0818445Y0499972*
X0818446Y0499972*
Y0499973*
X0818254Y0499935D02*
D01*
X0818288Y0499936*
X0818323Y0499939*
X0818357Y0499945*
X0818391Y0499954*
X0818425Y0499965*
X0818444Y0499972*
X0769004Y0551135D02*
D01*
X076847Y0551116*
X0767939Y055106*
X0767413Y0550967*
X0766895Y0550838*
X0766387Y0550673*
X0765892Y0550473*
X0765412Y0550239*
X076495Y0549972*
X0764507Y0549673*
X0764086Y0549345*
X0763689Y0548987*
X0763318Y0548603*
X0762975Y0548194*
X0762661Y0547762*
X0762378Y054731*
X0762128Y0546838*
X0761911Y054635*
X0761728Y0545848*
X0761581Y0545335*
X076147Y0544813*
X0761395Y0544284*
X0761358Y0543751*
X0761354Y0543485*
X0776654D02*
D01*
X0776635Y0544018*
X0776579Y0544549*
X0776486Y0545075*
X0776357Y0545593*
X0776192Y0546101*
X0775992Y0546596*
X0775758Y0547076*
X0775491Y0547538*
X0775192Y0547981*
X0774864Y0548402*
X0774506Y0548799*
X0774122Y054917*
X0773713Y0549513*
X0773281Y0549827*
X0772829Y055011*
X0772357Y055036*
X0771869Y0550577*
X0771367Y055076*
X0770854Y0550907*
X0770332Y0551018*
X0769803Y0551093*
X076927Y055113*
X0769004Y0551135*
Y0550135D02*
D01*
X076854Y0550118*
X0768078Y055007*
X0767621Y0549989*
X0767171Y0549877*
X0766729Y0549733*
X0766299Y054956*
X0765882Y0549356*
X076548Y0549124*
X0765095Y0548864*
X0764729Y0548579*
X0764384Y0548268*
X0764062Y0547934*
X0763763Y0547579*
X076349Y0547203*
X0763244Y054681*
X0763027Y05464*
X0762838Y0545976*
X0762679Y0545539*
X0762551Y0545093*
X0762455Y0544639*
X076239Y054418*
X0762358Y0543717*
X0762354Y0543485*
X0730754Y0550635D02*
D01*
X0730752Y0550669*
X0730749Y0550704*
X0730743Y0550738*
X0730734Y0550772*
X0730723Y0550806*
X073071Y0550838*
X0730695Y0550869*
X0730678Y0550899*
X0730658Y0550928*
X0730637Y0550956*
X0730613Y0550982*
X0730588Y0551006*
X0730561Y0551029*
X0730533Y0551049*
X0730504Y0551068*
X0730473Y0551084*
X0730441Y0551098*
X0730408Y055111*
X0730374Y055112*
X073034Y0551127*
X0730306Y0551132*
X0730271Y0551134*
X0730254Y0551135*
X0730754Y0550635D02*
D01*
X0730752Y0550669*
X0730749Y0550704*
X0730743Y0550738*
X0730734Y0550772*
X0730723Y0550806*
X073071Y0550838*
X0730695Y0550869*
X0730678Y0550899*
X0730658Y0550928*
X0730637Y0550956*
X0730613Y0550982*
X0730588Y0551006*
X0730561Y0551029*
X0730533Y0551049*
X0730504Y0551068*
X0730473Y0551084*
X0730441Y0551098*
X0730408Y055111*
X0730374Y055112*
X073034Y0551127*
X0730306Y0551132*
X0730271Y0551134*
X0730254Y0551135*
X0775654Y0543485D02*
D01*
X0775637Y0543948*
X0775589Y054441*
X0775508Y0544867*
X0775396Y0545317*
X0775252Y0545759*
X0775079Y0546189*
X0774875Y0546606*
X0774643Y0547008*
X0774383Y0547393*
X0774098Y0547759*
X0773787Y0548104*
X0773453Y0548426*
X0773098Y0548725*
X0772722Y0548998*
X0772329Y0549244*
X0771919Y0549461*
X0771495Y054965*
X0771058Y0549809*
X0770612Y0549937*
X0770158Y0550033*
X0769699Y0550098*
X0769236Y055013*
X0769004Y0550135*
X0658154Y0551135D02*
D01*
X0658119Y0551133*
X0658084Y055113*
X065805Y0551124*
X0658016Y0551115*
X0657982Y0551104*
X065795Y0551091*
X0657919Y0551076*
X0657889Y0551059*
X065786Y0551039*
X0657832Y0551018*
X0657806Y0550994*
X0657782Y0550969*
X0657759Y0550942*
X0657739Y0550914*
X065772Y0550885*
X0657704Y0550854*
X065769Y0550822*
X0657678Y0550789*
X0657668Y0550755*
X0657661Y0550721*
X0657656Y0550687*
X0657654Y0550652*
X0657654Y0550635*
X0658154Y0551135D02*
D01*
X0658119Y0551133*
X0658084Y055113*
X065805Y0551124*
X0658016Y0551115*
X0657982Y0551104*
X065795Y0551091*
X0657919Y0551076*
X0657889Y0551059*
X065786Y0551039*
X0657832Y0551018*
X0657806Y0550994*
X0657782Y0550969*
X0657759Y0550942*
X0657739Y0550914*
X065772Y0550885*
X0657704Y0550854*
X065769Y0550822*
X0657678Y0550789*
X0657668Y0550755*
X0657661Y0550721*
X0657656Y0550687*
X0657654Y0550652*
X0657654Y0550635*
X0599004Y0937317D02*
D01*
X0598969Y0937315*
X0598934Y0937312*
X05989Y0937306*
X0598866Y0937297*
X0598832Y0937286*
X05988Y0937273*
X0598769Y0937258*
X0598739Y0937241*
X059871Y0937221*
X0598682Y09372*
X0598656Y0937176*
X059865Y0937171*
X0598602Y0937122D02*
D01*
X0598578Y0937096*
X0598556Y0937069*
X0598535Y0937041*
X0598517Y0937011*
X0598501Y093698*
X0598488Y0936948*
X0598476Y0936915*
X0598467Y0936881*
X059846Y0936847*
X0598456Y0936812*
X0598454Y0936777*
X0598454Y0936767*
X0599004Y0937317D02*
D01*
X0598969Y0937315*
X0598934Y0937312*
X05989Y0937306*
X0598866Y0937297*
X0598832Y0937286*
X05988Y0937273*
X0598769Y0937258*
X0598739Y0937241*
X059871Y0937221*
X0598682Y09372*
X0598656Y0937176*
X0598649Y0937169*
X05986Y0937121D02*
D01*
X0598576Y0937095*
X0598554Y0937068*
X0598534Y0937039*
X0598516Y0937009*
X05985Y0936978*
X0598486Y0936946*
X0598475Y0936913*
X0598466Y0936879*
X0598459Y0936845*
X0598455Y093681*
X0598453Y0936775*
X0598454Y0936767*
X0777813Y0500098D02*
D01*
X0777838Y0500074*
X0777865Y0500052*
X0777893Y0500031*
X0777923Y0500013*
X0777954Y0499997*
X0777977Y0499988*
X0775654Y0502485D02*
D01*
X0775655Y050245*
X0775658Y0502415*
X0775664Y0502381*
X0775673Y0502347*
X0775684Y0502313*
X0775692Y0502294*
X0775707Y0502257D02*
D01*
X0775721Y0502225*
X0775738Y0502194*
X0775757Y0502165*
X0775777Y0502137*
X07758Y050211*
X0775815Y0502096*
X0775706Y0502259D02*
D01*
X0775706Y0502258*
X0775706Y0502258*
X0775706Y0502257*
X0775706Y0502257*
X0775707Y0502257*
Y0502258D02*
D01*
X0775721Y0502226*
X0775738Y0502195*
X0775756Y0502166*
X0775777Y0502138*
X07758Y0502111*
X0775817Y0502094*
X0775692Y0502295D02*
D01*
X0775692Y0502294*
X0775692Y0502294*
X0775692Y0502293*
X0775692Y0502293*
X0775692Y0502293*
X0775654Y0502485D02*
D01*
X0775655Y050245*
X0775658Y0502415*
X0775664Y0502381*
X0775673Y0502347*
X0775684Y0502313*
X0775692Y0502295*
X0818254Y0499935D02*
D01*
X0818288Y0499936*
X0818323Y0499939*
X0818357Y0499945*
X0818391Y0499954*
X0818425Y0499965*
X0818445Y0499973*
X0818482Y0499988D02*
D01*
X0818513Y0500002*
X0818544Y0500019*
X0818573Y0500038*
X0818601Y0500058*
X0818628Y0500081*
X0818643Y0500096*
X081848Y0499987D02*
D01*
X081848Y0499987*
X081848Y0499987*
X0818481Y0499987*
X0818481Y0499987*
X0818482Y0499987*
Y0499988*
X0777976D02*
D01*
X0777976Y0499987*
X0777976Y0499987*
X0777977Y0499987*
X0777977Y0499987*
X0777978Y0499987*
Y0499987*
X0777815Y0500096D02*
D01*
X077784Y0500072*
X0777867Y050005*
X0777896Y050003*
X0777926Y0500012*
X0777957Y0499996*
X0777976Y0499988*
X0778013Y0499973D02*
D01*
X0778045Y049996*
X0778079Y049995*
X0778113Y0499943*
X0778147Y0499938*
X0778182Y0499935*
X0778204Y0499935*
X0778014Y0499972D02*
D01*
X0778046Y0499959*
X077808Y049995*
X0778114Y0499942*
X0778148Y0499937*
X0778183Y0499934*
X0778204Y0499935*
X0778012Y0499973D02*
D01*
X0778012Y0499972*
X0778012Y0499972*
X0778013Y0499972*
X0778013Y0499972*
X0778014Y0499972*
Y0499972*
X0762206Y051783D02*
D01*
X0762229Y0517855*
X0762251Y0517882*
X0762272Y051791*
X076229Y051794*
X0762306Y0517971*
X0762319Y0518003*
X0762331Y0518036*
X076234Y051807*
X0762347Y0518104*
X0762351Y0518139*
X0762353Y0518174*
X0762354Y0518185*
X0762208Y0517831D02*
D01*
X0762231Y0517856*
X0762253Y0517883*
X0762273Y0517912*
X0762291Y0517942*
X0762307Y0517973*
X0762321Y0518005*
X0762332Y0518038*
X0762341Y0518072*
X0762348Y0518106*
X0762352Y0518141*
X0762354Y0518176*
X0762354Y0518185*
X0729754D02*
D01*
X0729755Y051815*
X0729758Y0518115*
X0729764Y0518081*
X0729773Y0518047*
X0729784Y0518013*
X0729797Y0517981*
X0729812Y051795*
X0729829Y051792*
X0729849Y0517891*
X072987Y0517863*
X0729894Y0517837*
X0729902Y051783*
X0761804Y0517635D02*
D01*
X0761838Y0517636*
X0761873Y0517639*
X0761907Y0517645*
X0761941Y0517654*
X0761975Y0517665*
X0762007Y0517678*
X0762038Y0517693*
X0762068Y051771*
X0762097Y051773*
X0762125Y0517751*
X0762151Y0517775*
X0762158Y0517781*
X0729949Y0517783D02*
D01*
X0729974Y0517759*
X0730001Y0517737*
X0730029Y0517716*
X0730059Y0517698*
X073009Y0517682*
X0730122Y0517669*
X0730155Y0517657*
X0730189Y0517648*
X0730223Y0517641*
X0730258Y0517637*
X0730293Y0517635*
X0730304Y0517635*
X0729754Y0518185D02*
D01*
X0729755Y051815*
X0729758Y0518115*
X0729764Y0518081*
X0729773Y0518047*
X0729784Y0518013*
X0729797Y0517981*
X0729812Y051795*
X0729829Y051792*
X0729849Y0517891*
X072987Y0517863*
X0729894Y0517837*
X07299Y0517831*
X0658508D02*
D01*
X0658531Y0517856*
X0658553Y0517883*
X0658573Y0517912*
X0658591Y0517942*
X0658607Y0517973*
X0658621Y0518005*
X0658632Y0518038*
X0658641Y0518072*
X0658648Y0518106*
X0658652Y0518141*
X0658654Y0518176*
X0658654Y0518185*
X0598454D02*
D01*
X0598455Y051815*
X0598458Y0518115*
X0598464Y0518081*
X0598473Y0518047*
X0598484Y0518013*
X0598497Y0517981*
X0598512Y051795*
X0598529Y051792*
X0598549Y0517891*
X059857Y0517863*
X0598594Y0517837*
X05986Y0517831*
X0658104Y0517635D02*
D01*
X0658138Y0517636*
X0658173Y0517639*
X0658207Y0517645*
X0658241Y0517654*
X0658275Y0517665*
X0658307Y0517678*
X0658338Y0517693*
X0658368Y051771*
X0658397Y051773*
X0658425Y0517751*
X0658451Y0517775*
X0658458Y0517781*
X0658506Y051783D02*
D01*
X0658529Y0517855*
X0658551Y0517882*
X0658572Y051791*
X065859Y051794*
X0658606Y0517971*
X0658619Y0518003*
X0658631Y0518036*
X065864Y051807*
X0658647Y0518104*
X0658651Y0518139*
X0658653Y0518174*
X0658654Y0518185*
X0598649Y0517783D02*
D01*
X0598674Y0517759*
X0598701Y0517737*
X0598729Y0517716*
X0598759Y0517698*
X059879Y0517682*
X0598822Y0517669*
X0598855Y0517657*
X0598889Y0517648*
X0598923Y0517641*
X0598958Y0517637*
X0598993Y0517635*
X0599004Y0517635*
X0761804D02*
D01*
X0761838Y0517636*
X0761873Y0517639*
X0761907Y0517645*
X0761941Y0517654*
X0761975Y0517665*
X0762007Y0517678*
X0762038Y0517693*
X0762068Y051771*
X0762097Y051773*
X0762125Y0517751*
X0762151Y0517775*
X0762159Y0517783*
X072995Y0517781D02*
D01*
X0729975Y0517757*
X0730002Y0517735*
X0730031Y0517715*
X0730061Y0517697*
X0730092Y0517681*
X0730124Y0517667*
X0730157Y0517656*
X0730191Y0517647*
X0730225Y051764*
X073026Y0517636*
X0730295Y0517634*
X0730304Y0517635*
X0598454Y0518185D02*
D01*
X0598455Y051815*
X0598458Y0518115*
X0598464Y0518081*
X0598473Y0518047*
X0598484Y0518013*
X0598497Y0517981*
X0598512Y051795*
X0598529Y051792*
X0598549Y0517891*
X059857Y0517863*
X0598594Y0517837*
X0598602Y051783*
X0658104Y0517635D02*
D01*
X0658138Y0517636*
X0658173Y0517639*
X0658207Y0517645*
X0658241Y0517654*
X0658275Y0517665*
X0658307Y0517678*
X0658338Y0517693*
X0658368Y051771*
X0658397Y051773*
X0658425Y0517751*
X0658451Y0517775*
X0658459Y0517783*
X059865Y0517781D02*
D01*
X0598675Y0517757*
X0598702Y0517735*
X0598731Y0517715*
X0598761Y0517697*
X0598792Y0517681*
X0598824Y0517667*
X0598857Y0517656*
X0598891Y0517647*
X0598925Y051764*
X059896Y0517636*
X0598995Y0517634*
X0599004Y0517635*
X1339909Y0937171D02*
X133991Y0937169D01*
X1339957Y0937122*
X1339959Y0937121*
X1340105Y0550585D02*
Y0936767D01*
X1339105Y0551035D02*
Y0936317D01*
X1339957Y055023D02*
X1339959Y0550231D01*
X133991Y0550183D02*
X1339957Y055023D01*
X1339909Y0550181D02*
X133991Y0550183D01*
X0911254Y0551035D02*
X1339105D01*
X0911754Y0550035D02*
X1339555D01*
X0911754Y0502485D02*
Y0550035D01*
X0823954Y0534035D02*
X0824054D01*
X0910754Y0502671D02*
Y0550535D01*
X0828204Y0502671D02*
Y0529885D01*
X0827204Y0502485D02*
Y0529885D01*
X0823954Y0533035D02*
X0824054D01*
X0819804Y0502671D02*
Y0529885D01*
X0911716Y0502294D02*
Y0502295D01*
Y0502293D02*
Y0502294D01*
X0911702Y0502259D02*
X0911716Y0502293D01*
X0911701Y0502258D02*
X0911702Y0502259D01*
X0911701Y0502257D02*
Y0502258D01*
X0909018Y0500935D02*
X0910754Y0502671D01*
X082994Y0500935D02*
X0909018D01*
X0828204Y0502671D02*
X082994Y0500935D01*
X0911591Y0502094D02*
X0911593Y0502096D01*
X0909595Y0500098D02*
X0911591Y0502094D01*
X0909593Y0500096D02*
X0909595Y0500098D01*
X0909431Y0499988D02*
X0909432D01*
X090943Y0499987D02*
X0909431Y0499988D01*
X0909396Y0499973D02*
X090943Y0499987D01*
X0909395Y0499973D02*
X0909396D01*
X0909394Y0499972D02*
X0909395Y0499973D01*
X0829754Y0499935D02*
X0909204D01*
X0827242Y0502295D02*
Y0502294D01*
Y0502293*
X0827256Y0502259*
X0827257Y0502258*
Y0502257*
X0820804Y0502485D02*
Y0529885D01*
X0820766Y0502294D02*
X0820767Y0502295D01*
X0820766Y0502293D02*
Y0502294D01*
X0820752Y0502259D02*
X0820766Y0502293D01*
X0820751Y0502258D02*
X0820752Y0502259D01*
X0820751Y0502257D02*
Y0502258D01*
X0827365Y0502096D02*
X0827367Y0502094D01*
X0829363Y0500098*
X0829365Y0500096*
X0820641Y0502094D02*
X0820643Y0502096D01*
X0818645Y0500098D02*
X0820641Y0502094D01*
X0818643Y0500096D02*
X0818645Y0500098D01*
X0829563Y0499973D02*
X0829564Y0499972D01*
X0829562Y0499973D02*
X0829563D01*
X0829528Y0499987D02*
X0829562Y0499973D01*
X0829527Y0499988D02*
X0829528Y0499987D01*
X0829526Y0499988D02*
X0829527D01*
X0818481D02*
X0818482D01*
X081848Y0499987D02*
X0818481Y0499988D01*
X0818446Y0499973D02*
X081848Y0499987D01*
X0818445Y0499973D02*
X0818446D01*
X0818444Y0499972D02*
X0818445Y0499973D01*
X0599004Y0937317D02*
X1339555D01*
X0599454Y0936317D02*
X1339105D01*
X0730754Y0518635D02*
Y0550635D01*
X0762354Y0518185D02*
Y0543485D01*
X0730754Y0518635D02*
X0761354D01*
Y0543485*
X0658154Y0551135D02*
X0730254D01*
X0599454Y0518635D02*
Y0936317D01*
X0598649Y0937169D02*
X059865Y0937171D01*
X0598602Y0937122D02*
X0598649Y0937169D01*
X05986Y0937121D02*
X0598602Y0937122D01*
X0598454Y0518185D02*
Y0936767D01*
X0658654Y0550135D02*
X0729754D01*
Y0518185D02*
Y0550135D01*
X0658654Y0518185D02*
Y0550135D01*
X0599454Y0518635D02*
X0657654D01*
Y0550635*
X0776654Y0502671D02*
Y0543485D01*
Y0502671D02*
X077839Y0500935D01*
X0818068D02*
X0819804Y0502671D01*
X0775692Y0502295D02*
Y0502294D01*
Y0502293*
X0775706Y0502259*
X0775707Y0502258*
Y0502257*
X0775815Y0502096D02*
X0775817Y0502094D01*
X0777813Y0500098*
X0777815Y0500096*
X077839Y0500935D02*
X0818068D01*
X0778013Y0499973D02*
X0778014Y0499972D01*
X0778012Y0499973D02*
X0778013D01*
X0777978Y0499987D02*
X0778012Y0499973D01*
X0777977Y0499988D02*
X0777978Y0499987D01*
X0777976Y0499988D02*
X0777977D01*
X0778204Y0499935D02*
X0818254D01*
X0775654Y0502485D02*
Y0543485D01*
X07299Y0517831D02*
X0729902Y051783D01*
X0729949Y0517783*
X072995Y0517781*
X0762206Y051783D02*
X0762208Y0517831D01*
X0762159Y0517783D02*
X0762206Y051783D01*
X0762158Y0517781D02*
X0762159Y0517783D01*
X0658506Y051783D02*
X0658508Y0517831D01*
X0658459Y0517783D02*
X0658506Y051783D01*
X0658458Y0517781D02*
X0658459Y0517783D01*
X0730304Y0517635D02*
X0761804D01*
X05986Y0517831D02*
X0598602Y051783D01*
X0598649Y0517783*
X059865Y0517781*
X0599004Y0517635D02*
X0658104D01*
G54D168*
X121789Y0880409D02*
Y0884346D01*
X120411Y0880409D02*
X121789D01*
X120411D02*
Y0884346D01*
X121789*
X1216905Y0904031D02*
Y0907969D01*
X1205095Y0904031D02*
X1216905D01*
X1205095D02*
Y0907969D01*
X1216905*
X1190528Y0888284D02*
X1194465D01*
X1190528D02*
Y0900095D01*
X1194465*
Y0888284D02*
Y0900095D01*
M02*